# BASEBOARD_FAB2 (Tioga Pass) — schematic netlist excerpt (pin names and nets, part order shuffled) for the footprints in the layout excerpt that follows; sources: Cadence DE-HDL packaged netlist, KiCad conversion of Wiwynn_Tioga_Pass_MB.brd

R2U22  RES  0.0 5% CHIP  pkg 0402  page 107 : A = P3E_CPU0_PE1_SS_RXP<4> ; B = P3E_CPU0_PE1_SS_R_RXP<4>
R2U25  RES  0.0 5% CHIP  pkg 0402  page 107 : A = P3E_CPU0_PE1_SS_RXN<5> ; B = P3E_CPU0_PE1_SS_R_RXN<5>
R1M19  RES  1.00K 1% CHIP  pkg 0402  page 113 : A = P1V8_MCP_CPU0 ; B = JTAG_MCP_TMS

(kicad_pcb
	(version 20260206)
	(generator "pcbnew")
	(generator_version "10.0")
	(general
		(thickness 1.6)
		(legacy_teardrops no)
	)
	(paper "A4")
	(title_block
		(title "Wiwynn_Tioga_Pass_MB.brd")
		(comment 1 "Tioga Pass / footprints 2813-2815 of 4770")
	)
	(layers
		(0 "F.Cu" signal "TOP")
		(4 "In1.Cu" signal "L2GND")
		(6 "In2.Cu" signal "L3")
		(8 "In3.Cu" signal "L4GND")
		(10 "In4.Cu" signal "L5")
		(12 "In5.Cu" signal "L6GND")
		(14 "In6.Cu" signal "L7VCC")
		(16 "In7.Cu" signal "L8VCC")
		(18 "In8.Cu" signal "L9GND")
		(20 "In9.Cu" signal "L10")
		(22 "In10.Cu" signal "L11GND")
		(24 "In11.Cu" signal "L12")
		(26 "In12.Cu" signal "L13GND")
		(2 "B.Cu" signal "BOTTOM")
		(9 "F.Adhes" user "F.Adhesive")
		(11 "B.Adhes" user "B.Adhesive")
		(13 "F.Paste" user "Package Geometry/Pastemask Top")
		(15 "B.Paste" user "Package Geometry/Pastemask Bottom")
		(5 "F.SilkS" user "Ref Des/Silkscreen Top")
		(7 "B.SilkS" user "Ref Des/Silkscreen Bottom")
		(1 "F.Mask" user "Board Geometry/Soldermask Top")
		(3 "B.Mask" user "Board Geometry/Soldermask Bottom")
		(17 "Dwgs.User" user "User.Drawings")
		(19 "Cmts.User" user "User.Comments")
		(21 "Eco1.User" user "User.Eco1")
		(23 "Eco2.User" user "User.Eco2")
		(25 "Edge.Cuts" user "Board Geometry/Outline")
		(27 "Margin" user)
		(31 "F.CrtYd" user "Package Geometry/Place Bound Top")
		(29 "B.CrtYd" user "Package Geometry/Place Bound Bottom")
		(35 "F.Fab" user "Ref Des/Assembly Top")
		(33 "B.Fab" user "Ref Des/Assembly Bottom")
	)
	(footprint ""
		(layer "B.Cu")
		(at 348.713806 -60.368434)
		(property "Reference" "R2U25"
			(at 0 0 0)
			(layer "B.SilkS")
			(hide yes)
			(effects
				(font
					(size 1.27 1.27)
				)
				(justify mirror)
			)
		)
		(property "Value" ""
			(at 0 0 0)
			(layer "B.Fab")
			(effects
				(font
					(size 1.27 1.27)
				)
				(justify mirror)
			)
		)
		(duplicate_pad_numbers_are_jumpers no)
		(fp_poly
			(pts
				(xy 0.2794 -0.1016) (xy -0.2794 -0.1016) (xy -0.2794 0.9906) (xy 0.2794 0.9906)
			)
			(stroke
				(width 0)
				(type default)
			)
			(fill no)
			(layer "B.CrtYd")
		)
		(fp_line
			(start -0.2794 -0.1016)
			(end 0.2794 -0.1016)
			(stroke
				(width 0.1)
				(type default)
			)
			(layer "B.Fab")
		)
		(fp_line
			(start -0.2794 0.9906)
			(end -0.2794 -0.1016)
			(stroke
				(width 0.1)
				(type default)
			)
			(layer "B.Fab")
		)
		(fp_line
			(start 0.2794 -0.1016)
			(end 0.2794 0.9906)
			(stroke
				(width 0.1)
				(type default)
			)
			(layer "B.Fab")
		)
		(fp_line
			(start 0.2794 0.9906)
			(end -0.2794 0.9906)
			(stroke
				(width 0.1)
				(type default)
			)
			(layer "B.Fab")
		)
		(pad "1" smd rect
			(at 0 0 180)
			(size 0.508 0.508)
			(layers "B.Cu" "B.Mask" "B.Paste")
			(net "P3E_CPU0_PE1_SS_RXN<5>")
		)
		(pad "2" smd rect
			(at 0 0.889 180)
			(size 0.508 0.508)
			(layers "B.Cu" "B.Mask" "B.Paste")
			(net "P3E_CPU0_PE1_SS_R_RXN<5>")
		)
		(zone
			(layer "B.Cu")
			(hatch none 0.5)
			(connect_pads
				(clearance 0)
			)
			(min_thickness 0.25)
			(keepout
				(tracks allowed)
				(vias not_allowed)
				(pads allowed)
				(copperpour not_allowed)
				(footprints allowed)
			)
			(placement
				(enabled no)
				(sheetname "")
			)
			(fill
				(thermal_gap 0.5)
				(thermal_bridge_width 0.5)
				(island_removal_mode 0)
			)
			(polygon
				(pts
					(xy 348.967806 -60.114434) (xy 348.459806 -60.114434) (xy 348.459806 -59.733434) (xy 348.967806 -59.733434)
				)
			)
		)
	)
	(footprint ""
		(layer "B.Cu")
		(at 344.522806 -60.368434)
		(property "Reference" "R2U22"
			(at 0 0 0)
			(layer "B.SilkS")
			(hide yes)
			(effects
				(font
					(size 1.27 1.27)
				)
				(justify mirror)
			)
		)
		(property "Value" ""
			(at 0 0 0)
			(layer "B.Fab")
			(effects
				(font
					(size 1.27 1.27)
				)
				(justify mirror)
			)
		)
		(duplicate_pad_numbers_are_jumpers no)
		(fp_poly
			(pts
				(xy 0.2794 -0.1016) (xy -0.2794 -0.1016) (xy -0.2794 0.9906) (xy 0.2794 0.9906)
			)
			(stroke
				(width 0)
				(type default)
			)
			(fill no)
			(layer "B.CrtYd")
		)
		(fp_line
			(start -0.2794 -0.1016)
			(end 0.2794 -0.1016)
			(stroke
				(width 0.1)
				(type default)
			)
			(layer "B.Fab")
		)
		(fp_line
			(start -0.2794 0.9906)
			(end -0.2794 -0.1016)
			(stroke
				(width 0.1)
				(type default)
			)
			(layer "B.Fab")
		)
		(fp_line
			(start 0.2794 -0.1016)
			(end 0.2794 0.9906)
			(stroke
				(width 0.1)
				(type default)
			)
			(layer "B.Fab")
		)
		(fp_line
			(start 0.2794 0.9906)
			(end -0.2794 0.9906)
			(stroke
				(width 0.1)
				(type default)
			)
			(layer "B.Fab")
		)
		(pad "1" smd rect
			(at 0 0 180)
			(size 0.508 0.508)
			(layers "B.Cu" "B.Mask" "B.Paste")
			(net "P3E_CPU0_PE1_SS_RXP<4>")
		)
		(pad "2" smd rect
			(at 0 0.889 180)
			(size 0.508 0.508)
			(layers "B.Cu" "B.Mask" "B.Paste")
			(net "P3E_CPU0_PE1_SS_R_RXP<4>")
		)
		(zone
			(layer "B.Cu")
			(hatch none 0.5)
			(connect_pads
				(clearance 0)
			)
			(min_thickness 0.25)
			(keepout
				(tracks allowed)
				(vias not_allowed)
				(pads allowed)
				(copperpour not_allowed)
				(footprints allowed)
			)
			(placement
				(enabled no)
				(sheetname "")
			)
			(fill
				(thermal_gap 0.5)
				(thermal_bridge_width 0.5)
				(island_removal_mode 0)
			)
			(polygon
				(pts
					(xy 344.776806 -60.114434) (xy 344.268806 -60.114434) (xy 344.268806 -59.733434) (xy 344.776806 -59.733434)
				)
			)
		)
	)
	(footprint ""
		(layer "B.Cu")
		(at 453.8472 -131.8514 -90)
		(property "Reference" "R1M19"
			(at 0 0 90)
			(layer "B.SilkS")
			(hide yes)
			(effects
				(font
					(size 1.27 1.27)
				)
				(justify mirror)
			)
		)
		(property "Value" ""
			(at 0 0 90)
			(layer "B.Fab")
			(effects
				(font
					(size 1.27 1.27)
				)
				(justify mirror)
			)
		)
		(duplicate_pad_numbers_are_jumpers no)
		(fp_poly
			(pts
				(xy 0.2794 -0.1016) (xy -0.2794 -0.1016) (xy -0.2794 0.9906) (xy 0.2794 0.9906)
			)
			(stroke
				(width 0)
				(type default)
			)
			(fill no)
			(layer "B.CrtYd")
		)
		(fp_line
			(start -0.2794 0.9906)
			(end -0.2794 -0.1016)
			(stroke
				(width 0.1)
				(type default)
			)
			(layer "B.Fab")
		)
		(fp_line
			(start 0.2794 0.9906)
			(end -0.2794 0.9906)
			(stroke
				(width 0.1)
				(type default)
			)
			(layer "B.Fab")
		)
		(fp_line
			(start -0.2794 -0.1016)
			(end 0.2794 -0.1016)
			(stroke
				(width 0.1)
				(type default)
			)
			(layer "B.Fab")
		)
		(fp_line
			(start 0.2794 -0.1016)
			(end 0.2794 0.9906)
			(stroke
				(width 0.1)
				(type default)
			)
			(layer "B.Fab")
		)
		(pad "1" smd rect
			(at 0 0 90)
			(size 0.508 0.508)
			(layers "B.Cu" "B.Mask" "B.Paste")
			(net "P1V8_MCP_CPU0")
		)
		(pad "2" smd rect
			(at 0 0.889 90)
			(size 0.508 0.508)
			(layers "B.Cu" "B.Mask" "B.Paste")
			(net "JTAG_MCP_TMS")
		)
		(zone
			(layer "B.Cu")
			(hatch none 0.5)
			(connect_pads
				(clearance 0)
			)
			(min_thickness 0.25)
			(keepout
				(tracks not_allowed)
				(vias allowed)
				(pads allowed)
				(copperpour not_allowed)
				(footprints allowed)
			)
			(placement
				(enabled no)
				(sheetname "")
			)
			(fill
				(thermal_gap 0.5)
				(thermal_bridge_width 0.5)
				(island_removal_mode 0)
			)
			(polygon
				(pts
					(xy 453.2122 -131.5974) (xy 453.2122 -132.1054) (xy 453.5932 -132.1054) (xy 453.5932 -131.5974)
				)
			)
		)
		(zone
			(layer "B.Cu")
			(hatch none 0.5)
			(connect_pads
				(clearance 0)
			)
			(min_thickness 0.25)
			(keepout
				(tracks allowed)
				(vias not_allowed)
				(pads allowed)
				(copperpour not_allowed)
				(footprints allowed)
			)
			(placement
				(enabled no)
				(sheetname "")
			)
			(fill
				(thermal_gap 0.5)
				(thermal_bridge_width 0.5)
				(island_removal_mode 0)
			)
			(polygon
				(pts
					(xy 453.5932 -131.5974) (xy 453.5932 -132.1054) (xy 453.2122 -132.1054) (xy 453.2122 -131.5974)
				)
			)
		)
	)
)
